FILE_TYPE = CONNECTIVITY;
{Allegro Design Entry HDL 16.6-p007 (v16-6-112F) 10/10/2012}
"PAGE_NUMBER" = 19;
0"NC";
END.
